(kicad_pcb
	(version 20260206)
	(generator "pcbnew")
	(generator_version "10.0")
	(general
		(thickness 1.6)
		(legacy_teardrops no)
	)
	(paper "A4")
	(title_block
		(title "Bryce Canyon_SCC_16316-1_OCP.brd")
		(comment 1 "Bryce Canyon / footprints 961-967 of 1561")
	)
	(layers
		(0 "F.Cu" signal "TOP")
		(4 "In1.Cu" signal "L2GND")
		(6 "In2.Cu" signal "L3")
		(8 "In3.Cu" signal "L4VCC")
		(10 "In4.Cu" signal "L5VCC")
		(12 "In5.Cu" signal "L6")
		(14 "In6.Cu" signal "L7GND")
		(2 "B.Cu" signal "BOTTOM")
		(9 "F.Adhes" user "F.Adhesive")
		(11 "B.Adhes" user "B.Adhesive")
		(13 "F.Paste" user "Package Geometry/Pastemask Top")
		(15 "B.Paste" user "Package Geometry/Pastemask Bottom")
		(5 "F.SilkS" user "Ref Des/Silkscreen Top")
		(7 "B.SilkS" user "Ref Des/Silkscreen Bottom")
		(1 "F.Mask" user "Board Geometry/Soldermask Top")
		(3 "B.Mask" user "Board Geometry/Soldermask Bottom")
		(17 "Dwgs.User" user "User.Drawings")
		(19 "Cmts.User" user "User.Comments")
		(21 "Eco1.User" user "User.Eco1")
		(23 "Eco2.User" user "User.Eco2")
		(25 "Edge.Cuts" user "Board Geometry/Outline")
		(27 "Margin" user)
		(31 "F.CrtYd" user "Package Geometry/Place Bound Top")
		(29 "B.CrtYd" user "Package Geometry/Place Bound Bottom")
		(35 "F.Fab" user "Ref Des/Assembly Top")
		(33 "B.Fab" user "Ref Des/Assembly Bottom")
	)
	(footprint ""
		(layer "B.Cu")
		(at 177.805842 -41.888156 90)
		(property "Reference" "C415"
			(at 0 0 90)
			(layer "B.SilkS")
			(hide yes)
			(effects
				(font
					(size 1.27 1.27)
				)
				(justify mirror)
			)
		)
		(property "Value" "SC1U6D3V1MX-GP"
			(at -1.9177 2.0193 90)
			(unlocked yes)
			(layer "B.Fab")
			(hide yes)
			(effects
				(font
					(size 1.016 1.016)
					(thickness 0.1524)
				)
				(justify mirror)
			)
		)
		(property "Device Type" "C0201H14"
			(at -1.9177 0.4953 90)
			(unlocked yes)
			(layer "B.Fab")
			(hide yes)
			(effects
				(font
					(size 1.016 1.016)
					(thickness 0.1524)
				)
				(justify mirror)
			)
		)
		(duplicate_pad_numbers_are_jumpers no)
		(fp_rect
			(start 0.1524 0.3048)
			(end -0.1524 -0.3048)
			(stroke
				(width 0)
				(type default)
			)
			(fill no)
			(layer "B.CrtYd")
		)
		(fp_poly
			(pts
				(xy 0.2794 0.6477) (xy 0.2794 -0.6477) (xy -0.2794 -0.6477) (xy -0.2794 -0.1905) (xy -0.1524 -0.1905)
				(xy -0.1524 -0.3048) (xy 0.1524 -0.3048) (xy 0.1524 0.3048) (xy -0.1524 0.3048) (xy -0.1524 -0.1778)
				(xy -0.2794 -0.1778) (xy -0.2794 0.6477)
			)
			(stroke
				(width 0)
				(type default)
			)
			(fill no)
			(layer "B.CrtYd")
		)
		(fp_rect
			(start 0.2794 0.6477)
			(end -0.2794 -0.6477)
			(stroke
				(width 0)
				(type default)
			)
			(fill no)
			(layer "B.Fab")
		)
		(pad "1" smd custom
			(at 0 -0.2794 270)
			(size 0.0762 0.0762)
			(layers "B.Cu" "B.Mask" "B.Paste")
			(net "P0V975")
			(options
				(clearance outline)
				(anchor circle)
			)
			(primitives
				(gr_poly
					(pts
						(arc
							(start 0.1524 0.127)
							(mid 0.137521 0.162921)
							(end 0.1016 0.1778)
						)
						(arc
							(start -0.1016 0.1778)
							(mid -0.137521 0.162921)
							(end -0.1524 0.127)
						)
						(arc
							(start -0.1524 -0.127)
							(mid -0.137521 -0.162921)
							(end -0.1016 -0.1778)
						)
						(arc
							(start 0.1016 -0.1778)
							(mid 0.137521 -0.162921)
							(end 0.1524 -0.127)
						)
					)
					(width 0)
					(fill yes)
				)
			)
		)
		(pad "2" smd custom
			(at 0 0.2794 270)
			(size 0.0762 0.0762)
			(layers "B.Cu" "B.Mask" "B.Paste")
			(net "GND")
			(options
				(clearance outline)
				(anchor circle)
			)
			(primitives
				(gr_poly
					(pts
						(arc
							(start 0.1524 0.127)
							(mid 0.137521 0.162921)
							(end 0.1016 0.1778)
						)
						(arc
							(start -0.1016 0.1778)
							(mid -0.137521 0.162921)
							(end -0.1524 0.127)
						)
						(arc
							(start -0.1524 -0.127)
							(mid -0.137521 -0.162921)
							(end -0.1016 -0.1778)
						)
						(arc
							(start 0.1016 -0.1778)
							(mid 0.137521 -0.162921)
							(end 0.1524 -0.127)
						)
					)
					(width 0)
					(fill yes)
				)
			)
		)
	)
	(footprint ""
		(layer "B.Cu")
		(at 131.449318 -87.260684 180)
		(property "Reference" "R36"
			(at 0 0 0)
			(layer "B.SilkS")
			(hide yes)
			(effects
				(font
					(size 1.27 1.27)
				)
				(justify mirror)
			)
		)
		(property "Value" "4K7R2F-GP"
			(at -0.064008 -3.993896 180)
			(unlocked yes)
			(layer "B.Fab")
			(hide yes)
			(effects
				(font
					(size 1.016 1.016)
					(thickness 0.1524)
				)
				(justify mirror)
			)
		)
		(property "Device Type" "R402H16"
			(at -0.064008 -5.517896 180)
			(unlocked yes)
			(layer "B.Fab")
			(hide yes)
			(effects
				(font
					(size 1.016 1.016)
					(thickness 0.1524)
				)
				(justify mirror)
			)
		)
		(duplicate_pad_numbers_are_jumpers no)
		(fp_line
			(start 0.508 -0.9398)
			(end 0.508 0.9398)
			(stroke
				(width 0.1524)
				(type default)
			)
			(layer "B.SilkS")
		)
		(fp_line
			(start -0.508 -0.9398)
			(end 0.508 -0.9398)
			(stroke
				(width 0.1524)
				(type default)
			)
			(layer "B.SilkS")
		)
		(fp_rect
			(start 0.508 0.9398)
			(end -0.508 -0.9398)
			(stroke
				(width 0)
				(type default)
			)
			(fill no)
			(layer "B.CrtYd")
		)
		(fp_rect
			(start 0.508 0.9398)
			(end -0.508 -0.9398)
			(stroke
				(width 0)
				(type default)
			)
			(fill no)
			(layer "B.Fab")
		)
		(pad "1" smd custom
			(at 0 -0.4445)
			(size 0.1397 0.1397)
			(layers "B.Cu" "B.Mask" "B.Paste")
			(net "EXP_SIO_LOAD_IN")
			(options
				(clearance outline)
				(anchor circle)
			)
			(primitives
				(gr_poly
					(pts
						(arc
							(start -0.1778 0.2794)
							(mid -0.249642 0.249642)
							(end -0.2794 0.1778)
						)
						(arc
							(start -0.2794 -0.1778)
							(mid -0.249642 -0.249642)
							(end -0.1778 -0.2794)
						)
						(arc
							(start 0.1778 -0.2794)
							(mid 0.249642 -0.249642)
							(end 0.2794 -0.1778)
						)
						(arc
							(start 0.2794 0.1778)
							(mid 0.249642 0.249642)
							(end 0.1778 0.2794)
						)
					)
					(width 0)
					(fill yes)
				)
			)
		)
		(pad "2" smd custom
			(at 0 0.4445)
			(size 0.1397 0.1397)
			(layers "B.Cu" "B.Mask" "B.Paste")
			(net "P1V8_E")
			(options
				(clearance outline)
				(anchor circle)
			)
			(primitives
				(gr_poly
					(pts
						(arc
							(start -0.1778 0.2794)
							(mid -0.249642 0.249642)
							(end -0.2794 0.1778)
						)
						(arc
							(start -0.2794 -0.1778)
							(mid -0.249642 -0.249642)
							(end -0.1778 -0.2794)
						)
						(arc
							(start 0.1778 -0.2794)
							(mid 0.249642 -0.249642)
							(end 0.2794 -0.1778)
						)
						(arc
							(start 0.2794 0.1778)
							(mid 0.249642 0.249642)
							(end 0.1778 0.2794)
						)
					)
					(width 0)
					(fill yes)
				)
			)
		)
	)
	(footprint ""
		(layer "B.Cu")
		(at 162.33648 -115.60302 180)
		(property "Reference" "R28"
			(at 0 0 0)
			(layer "B.SilkS")
			(hide yes)
			(effects
				(font
					(size 1.27 1.27)
				)
				(justify mirror)
			)
		)
		(property "Value" "2D2R3J-2-GP"
			(at 0.0254 -2.5146 180)
			(unlocked yes)
			(layer "B.Fab")
			(hide yes)
			(effects
				(font
					(size 1.016 1.016)
					(thickness 0.1524)
				)
				(justify mirror)
			)
		)
		(property "Device Type" "R603H22"
			(at 0.0254 -4.0386 180)
			(unlocked yes)
			(layer "B.Fab")
			(hide yes)
			(effects
				(font
					(size 1.016 1.016)
					(thickness 0.1524)
				)
				(justify mirror)
			)
		)
		(duplicate_pad_numbers_are_jumpers no)
		(fp_line
			(start 0.4826 0)
			(end 0.2032 0)
			(stroke
				(width 0.2032)
				(type default)
			)
			(layer "B.SilkS")
		)
		(fp_line
			(start -0.2032 0)
			(end -0.4826 0)
			(stroke
				(width 0.2032)
				(type default)
			)
			(layer "B.SilkS")
		)
		(fp_rect
			(start 0.5842 1.3335)
			(end -0.5842 -1.3335)
			(stroke
				(width 0)
				(type default)
			)
			(fill no)
			(layer "B.CrtYd")
		)
		(fp_rect
			(start 0.5842 1.3335)
			(end -0.5842 -1.3335)
			(stroke
				(width 0)
				(type default)
			)
			(fill no)
			(layer "B.Fab")
		)
		(pad "1" smd custom
			(at 0 -0.762)
			(size 0.2159 0.2159)
			(layers "B.Cu" "B.Mask" "B.Paste")
			(net "P12V_STBY_VDD_U11")
			(options
				(clearance outline)
				(anchor circle)
			)
			(primitives
				(gr_poly
					(pts
						(arc
							(start -0.3302 0.4318)
							(mid -0.402042 0.402042)
							(end -0.4318 0.3302)
						)
						(arc
							(start -0.4318 -0.3302)
							(mid -0.402042 -0.402042)
							(end -0.3302 -0.4318)
						)
						(arc
							(start 0.3302 -0.4318)
							(mid 0.402042 -0.402042)
							(end 0.4318 -0.3302)
						)
						(arc
							(start 0.4318 0.3302)
							(mid 0.402042 0.402042)
							(end 0.3302 0.4318)
						)
					)
					(width 0)
					(fill yes)
				)
			)
		)
		(pad "2" smd custom
			(at 0 0.762)
			(size 0.2159 0.2159)
			(layers "B.Cu" "B.Mask" "B.Paste")
			(net "P12V_STBY_SCC")
			(options
				(clearance outline)
				(anchor circle)
			)
			(primitives
				(gr_poly
					(pts
						(arc
							(start -0.3302 0.4318)
							(mid -0.402042 0.402042)
							(end -0.4318 0.3302)
						)
						(arc
							(start -0.4318 -0.3302)
							(mid -0.402042 -0.402042)
							(end -0.3302 -0.4318)
						)
						(arc
							(start 0.3302 -0.4318)
							(mid 0.402042 -0.402042)
							(end 0.4318 -0.3302)
						)
						(arc
							(start 0.4318 0.3302)
							(mid 0.402042 0.402042)
							(end 0.3302 0.4318)
						)
					)
					(width 0)
					(fill yes)
				)
			)
		)
	)
	(footprint ""
		(layer "B.Cu")
		(at 117.856 -86.995 180)
		(property "Reference" "R146"
			(at 0 0 0)
			(layer "B.SilkS")
			(hide yes)
			(effects
				(font
					(size 1.27 1.27)
				)
				(justify mirror)
			)
		)
		(property "Value" "4K7R2F-GP"
			(at -0.064008 -3.993896 180)
			(unlocked yes)
			(layer "B.Fab")
			(hide yes)
			(effects
				(font
					(size 1.016 1.016)
					(thickness 0.1524)
				)
				(justify mirror)
			)
		)
		(property "Device Type" "R402H16"
			(at -0.064008 -5.517896 180)
			(unlocked yes)
			(layer "B.Fab")
			(hide yes)
			(effects
				(font
					(size 1.016 1.016)
					(thickness 0.1524)
				)
				(justify mirror)
			)
		)
		(duplicate_pad_numbers_are_jumpers no)
		(fp_line
			(start 0.508 -0.9398)
			(end 0.508 0.9398)
			(stroke
				(width 0.1524)
				(type default)
			)
			(layer "B.SilkS")
		)
		(fp_line
			(start -0.508 -0.9398)
			(end 0.508 -0.9398)
			(stroke
				(width 0.1524)
				(type default)
			)
			(layer "B.SilkS")
		)
		(fp_rect
			(start 0.508 0.9398)
			(end -0.508 -0.9398)
			(stroke
				(width 0)
				(type default)
			)
			(fill no)
			(layer "B.CrtYd")
		)
		(fp_rect
			(start 0.508 0.9398)
			(end -0.508 -0.9398)
			(stroke
				(width 0)
				(type default)
			)
			(fill no)
			(layer "B.Fab")
		)
		(pad "1" smd custom
			(at 0 -0.4445)
			(size 0.1397 0.1397)
			(layers "B.Cu" "B.Mask" "B.Paste")
			(net "EXP_XM_ADDR_23")
			(options
				(clearance outline)
				(anchor circle)
			)
			(primitives
				(gr_poly
					(pts
						(arc
							(start -0.1778 0.2794)
							(mid -0.249642 0.249642)
							(end -0.2794 0.1778)
						)
						(arc
							(start -0.2794 -0.1778)
							(mid -0.249642 -0.249642)
							(end -0.1778 -0.2794)
						)
						(arc
							(start 0.1778 -0.2794)
							(mid 0.249642 -0.249642)
							(end 0.2794 -0.1778)
						)
						(arc
							(start 0.2794 0.1778)
							(mid 0.249642 0.249642)
							(end 0.1778 0.2794)
						)
					)
					(width 0)
					(fill yes)
				)
			)
		)
		(pad "2" smd custom
			(at 0 0.4445)
			(size 0.1397 0.1397)
			(layers "B.Cu" "B.Mask" "B.Paste")
			(net "GND")
			(options
				(clearance outline)
				(anchor circle)
			)
			(primitives
				(gr_poly
					(pts
						(arc
							(start -0.1778 0.2794)
							(mid -0.249642 0.249642)
							(end -0.2794 0.1778)
						)
						(arc
							(start -0.2794 -0.1778)
							(mid -0.249642 -0.249642)
							(end -0.1778 -0.2794)
						)
						(arc
							(start 0.1778 -0.2794)
							(mid 0.249642 -0.249642)
							(end 0.2794 -0.1778)
						)
						(arc
							(start 0.2794 0.1778)
							(mid 0.249642 0.249642)
							(end 0.1778 0.2794)
						)
					)
					(width 0)
					(fill yes)
				)
			)
		)
	)
	(footprint ""
		(layer "B.Cu")
		(at 100.584 -86.9696 180)
		(property "Reference" "R72"
			(at 0 0 0)
			(layer "B.SilkS")
			(hide yes)
			(effects
				(font
					(size 1.27 1.27)
				)
				(justify mirror)
			)
		)
		(property "Value" "4K7R2F-GP"
			(at -0.064008 -3.993896 180)
			(unlocked yes)
			(layer "B.Fab")
			(hide yes)
			(effects
				(font
					(size 1.016 1.016)
					(thickness 0.1524)
				)
				(justify mirror)
			)
		)
		(property "Device Type" "R402H16"
			(at -0.064008 -5.517896 180)
			(unlocked yes)
			(layer "B.Fab")
			(hide yes)
			(effects
				(font
					(size 1.016 1.016)
					(thickness 0.1524)
				)
				(justify mirror)
			)
		)
		(duplicate_pad_numbers_are_jumpers no)
		(fp_line
			(start 0.508 -0.9398)
			(end 0.508 0.9398)
			(stroke
				(width 0.1524)
				(type default)
			)
			(layer "B.SilkS")
		)
		(fp_line
			(start -0.508 -0.9398)
			(end 0.508 -0.9398)
			(stroke
				(width 0.1524)
				(type default)
			)
			(layer "B.SilkS")
		)
		(fp_rect
			(start 0.508 0.9398)
			(end -0.508 -0.9398)
			(stroke
				(width 0)
				(type default)
			)
			(fill no)
			(layer "B.CrtYd")
		)
		(fp_rect
			(start 0.508 0.9398)
			(end -0.508 -0.9398)
			(stroke
				(width 0)
				(type default)
			)
			(fill no)
			(layer "B.Fab")
		)
		(pad "1" smd custom
			(at 0 -0.4445)
			(size 0.1397 0.1397)
			(layers "B.Cu" "B.Mask" "B.Paste")
			(net "P1V8_E")
			(options
				(clearance outline)
				(anchor circle)
			)
			(primitives
				(gr_poly
					(pts
						(arc
							(start -0.1778 0.2794)
							(mid -0.249642 0.249642)
							(end -0.2794 0.1778)
						)
						(arc
							(start -0.2794 -0.1778)
							(mid -0.249642 -0.249642)
							(end -0.1778 -0.2794)
						)
						(arc
							(start 0.1778 -0.2794)
							(mid 0.249642 -0.249642)
							(end 0.2794 -0.1778)
						)
						(arc
							(start 0.2794 0.1778)
							(mid 0.249642 0.249642)
							(end 0.1778 0.2794)
						)
					)
					(width 0)
					(fill yes)
				)
			)
		)
		(pad "2" smd custom
			(at 0 0.4445)
			(size 0.1397 0.1397)
			(layers "B.Cu" "B.Mask" "B.Paste")
			(net "SCC_TYPE_0_LS")
			(options
				(clearance outline)
				(anchor circle)
			)
			(primitives
				(gr_poly
					(pts
						(arc
							(start -0.1778 0.2794)
							(mid -0.249642 0.249642)
							(end -0.2794 0.1778)
						)
						(arc
							(start -0.2794 -0.1778)
							(mid -0.249642 -0.249642)
							(end -0.1778 -0.2794)
						)
						(arc
							(start 0.1778 -0.2794)
							(mid 0.249642 -0.249642)
							(end 0.2794 -0.1778)
						)
						(arc
							(start 0.2794 0.1778)
							(mid 0.249642 0.249642)
							(end 0.1778 0.2794)
						)
					)
					(width 0)
					(fill yes)
				)
			)
		)
	)
	(footprint ""
		(layer "B.Cu")
		(at 179.451 -30.353 -90)
		(property "Reference" "C486"
			(at 0 0 90)
			(layer "B.SilkS")
			(hide yes)
			(effects
				(font
					(size 1.27 1.27)
				)
				(justify mirror)
			)
		)
		(property "Value" "SC1U16V2KX-7-GP"
			(at -1.7526 -1.6002 270)
			(unlocked yes)
			(layer "B.Fab")
			(hide yes)
			(effects
				(font
					(size 1.016 1.016)
					(thickness 0.1524)
				)
				(justify mirror)
			)
		)
		(property "Device Type" "C402-TO0D2H24"
			(at -1.7526 -3.1242 270)
			(unlocked yes)
			(layer "B.Fab")
			(hide yes)
			(effects
				(font
					(size 1.016 1.016)
					(thickness 0.1524)
				)
				(justify mirror)
			)
		)
		(duplicate_pad_numbers_are_jumpers no)
		(fp_rect
			(start 0.4826 0.889)
			(end -0.4826 -0.889)
			(stroke
				(width 0)
				(type default)
			)
			(fill no)
			(layer "B.CrtYd")
		)
		(fp_rect
			(start 0.4826 0.889)
			(end -0.4826 -0.889)
			(stroke
				(width 0)
				(type default)
			)
			(fill no)
			(layer "B.Fab")
		)
		(pad "1" smd custom
			(at 0 -0.4572 90)
			(size 0.1524 0.1524)
			(layers "B.Cu" "B.Mask" "B.Paste")
			(net "P1V8_C")
			(options
				(clearance outline)
				(anchor circle)
			)
			(primitives
				(gr_poly
					(pts
						(arc
							(start -0.254 -0.3048)
							(mid -0.325842 -0.275042)
							(end -0.3556 -0.2032)
						)
						(arc
							(start -0.3556 0.2032)
							(mid -0.325842 0.275042)
							(end -0.254 0.3048)
						)
						(arc
							(start 0.254 0.3048)
							(mid 0.325842 0.275042)
							(end 0.3556 0.2032)
						)
						(arc
							(start 0.3556 -0.2032)
							(mid 0.325842 -0.275042)
							(end 0.254 -0.3048)
						)
					)
					(width 0)
					(fill yes)
				)
			)
		)
		(pad "2" smd custom
			(at 0 0.4572 90)
			(size 0.1524 0.1524)
			(layers "B.Cu" "B.Mask" "B.Paste")
			(net "GND")
			(options
				(clearance outline)
				(anchor circle)
			)
			(primitives
				(gr_poly
					(pts
						(arc
							(start -0.254 -0.3048)
							(mid -0.325842 -0.275042)
							(end -0.3556 -0.2032)
						)
						(arc
							(start -0.3556 0.2032)
							(mid -0.325842 0.275042)
							(end -0.254 0.3048)
						)
						(arc
							(start 0.254 0.3048)
							(mid 0.325842 0.275042)
							(end 0.3556 0.2032)
						)
						(arc
							(start 0.3556 -0.2032)
							(mid 0.325842 -0.275042)
							(end 0.254 -0.3048)
						)
					)
					(width 0)
					(fill yes)
				)
			)
		)
	)
	(footprint ""
		(layer "B.Cu")
		(at 201.168 -58.674 180)
		(property "Reference" "R300"
			(at 0 0 0)
			(layer "B.SilkS")
			(hide yes)
			(effects
				(font
					(size 1.27 1.27)
				)
				(justify mirror)
			)
		)
		(property "Value" "10KR2F-2-GP"
			(at -0.064008 -3.993896 180)
			(unlocked yes)
			(layer "B.Fab")
			(hide yes)
			(effects
				(font
					(size 1.016 1.016)
					(thickness 0.1524)
				)
				(justify mirror)
			)
		)
		(property "Device Type" "R402H16"
			(at -0.064008 -5.517896 180)
			(unlocked yes)
			(layer "B.Fab")
			(hide yes)
			(effects
				(font
					(size 1.016 1.016)
					(thickness 0.1524)
				)
				(justify mirror)
			)
		)
		(duplicate_pad_numbers_are_jumpers no)
		(fp_line
			(start 0.508 -0.9398)
			(end 0.508 0.9398)
			(stroke
				(width 0.1524)
				(type default)
			)
			(layer "B.SilkS")
		)
		(fp_line
			(start -0.508 -0.9398)
			(end 0.508 -0.9398)
			(stroke
				(width 0.1524)
				(type default)
			)
			(layer "B.SilkS")
		)
		(fp_rect
			(start 0.508 0.9398)
			(end -0.508 -0.9398)
			(stroke
				(width 0)
				(type default)
			)
			(fill no)
			(layer "B.CrtYd")
		)
		(fp_rect
			(start 0.508 0.9398)
			(end -0.508 -0.9398)
			(stroke
				(width 0)
				(type default)
			)
			(fill no)
			(layer "B.Fab")
		)
		(pad "1" smd custom
			(at 0 -0.4445)
			(size 0.1397 0.1397)
			(layers "B.Cu" "B.Mask" "B.Paste")
			(net "P1V8_C")
			(options
				(clearance outline)
				(anchor circle)
			)
			(primitives
				(gr_poly
					(pts
						(arc
							(start -0.1778 0.2794)
							(mid -0.249642 0.249642)
							(end -0.2794 0.1778)
						)
						(arc
							(start -0.2794 -0.1778)
							(mid -0.249642 -0.249642)
							(end -0.1778 -0.2794)
						)
						(arc
							(start 0.1778 -0.2794)
							(mid 0.249642 -0.249642)
							(end 0.2794 -0.1778)
						)
						(arc
							(start 0.2794 0.1778)
							(mid 0.249642 0.249642)
							(end 0.1778 0.2794)
						)
					)
					(width 0)
					(fill yes)
				)
			)
		)
		(pad "2" smd custom
			(at 0 0.4445)
			(size 0.1397 0.1397)
			(layers "B.Cu" "B.Mask" "B.Paste")
			(net "IOC_BYTE_N")
			(options
				(clearance outline)
				(anchor circle)
			)
			(primitives
				(gr_poly
					(pts
						(arc
							(start -0.1778 0.2794)
							(mid -0.249642 0.249642)
							(end -0.2794 0.1778)
						)
						(arc
							(start -0.2794 -0.1778)
							(mid -0.249642 -0.249642)
							(end -0.1778 -0.2794)
						)
						(arc
							(start 0.1778 -0.2794)
							(mid 0.249642 -0.249642)
							(end 0.2794 -0.1778)
						)
						(arc
							(start 0.2794 0.1778)
							(mid 0.249642 0.249642)
							(end 0.1778 0.2794)
						)
					)
					(width 0)
					(fill yes)
				)
			)
		)
	)
)
